# T6G (Grand Teton) — schematic netlist excerpt (pin names and nets, part order shuffled) for the footprints in the layout excerpt that follows; sources: Cadence DE-HDL packaged netlist, KiCad conversion of 04192023_DAF0TMB3IC0_F0TG_MB_C_brd_V02_OCP.brd

PC114  Q_CAP  22UF 4V 20% X6S  pkg C0805  page 209 : A = PVDD18_S5_P0 ; B = GND
R6007  Q_RES  0 5% CHIP  pkg 0402LF  page 150 : A = I3C_SCM_3_SDA ; B = I3C_SCM_3_R_SDA
PC182_4  Q_CAP  22UF 16V 20% X6S  pkg C0805  page 206 : A = SW_P12V_AUX_PVDDIO_P0_FLT ; B = GND

(kicad_pcb
	(version 20260206)
	(generator "pcbnew")
	(generator_version "10.0")
	(general
		(thickness 1.6)
		(legacy_teardrops no)
	)
	(paper "A4")
	(title_block
		(title "04192023_DAF0TMB3IC0_F0TG_MB_C_brd_V02_OCP.brd")
		(comment 1 "Grand Teton / footprints 7540-7542 of 8354")
	)
	(layers
		(0 "F.Cu" signal "TOP")
		(4 "In1.Cu" signal "GND")
		(6 "In2.Cu" signal "IN1")
		(8 "In3.Cu" signal "GND1")
		(10 "In4.Cu" signal "IN2")
		(12 "In5.Cu" signal "GND2")
		(14 "In6.Cu" signal "IN3")
		(16 "In7.Cu" signal "GND3")
		(18 "In8.Cu" signal "VCC")
		(20 "In9.Cu" signal "VCC1")
		(22 "In10.Cu" signal "GND4")
		(24 "In11.Cu" signal "IN4")
		(26 "In12.Cu" signal "GND5")
		(28 "In13.Cu" signal "IN5")
		(30 "In14.Cu" signal "GND6")
		(32 "In15.Cu" signal "IN6")
		(34 "In16.Cu" signal "GND7")
		(2 "B.Cu" signal "BOTTOM")
		(9 "F.Adhes" user "F.Adhesive")
		(11 "B.Adhes" user "B.Adhesive")
		(13 "F.Paste" user "Package Geometry/Pastemask Top")
		(15 "B.Paste" user "Package Geometry/Pastemask Bottom")
		(5 "F.SilkS" user "Ref Des/Silkscreen Top")
		(7 "B.SilkS" user "Ref Des/Silkscreen Bottom")
		(1 "F.Mask" user "Board Geometry/Soldermask Top")
		(3 "B.Mask" user "Board Geometry/Soldermask Bottom")
		(17 "Dwgs.User" user "User.Drawings")
		(19 "Cmts.User" user "User.Comments")
		(21 "Eco1.User" user "User.Eco1")
		(23 "Eco2.User" user "User.Eco2")
		(25 "Edge.Cuts" user "Board Geometry/Outline")
		(27 "Margin" user)
		(31 "F.CrtYd" user "Package Geometry/Place Bound Top")
		(29 "B.CrtYd" user "Package Geometry/Place Bound Bottom")
		(35 "F.Fab" user "Ref Des/Assembly Top")
		(33 "B.Fab" user "Ref Des/Assembly Bottom")
	)
	(footprint ""
		(layer "B.Cu")
		(at 182.8673 -13.60043 -90)
		(property "Reference" "R6007"
			(at 0 0 90)
			(layer "B.SilkS")
			(hide yes)
			(effects
				(font
					(size 1.27 1.27)
				)
				(justify mirror)
			)
		)
		(property "Value" ""
			(at 0 0 90)
			(layer "B.Fab")
			(effects
				(font
					(size 1.27 1.27)
				)
				(justify mirror)
			)
		)
		(duplicate_pad_numbers_are_jumpers no)
		(fp_line
			(start -0.7874 0.4064)
			(end 0.7874 0.4064)
			(stroke
				(width 0.1524)
				(type default)
			)
			(layer "B.SilkS")
		)
		(fp_line
			(start 0.7874 0.4064)
			(end 0.7874 -0.4064)
			(stroke
				(width 0.1524)
				(type default)
			)
			(layer "B.SilkS")
		)
		(fp_line
			(start -0.7874 -0.4064)
			(end -0.7874 0.4064)
			(stroke
				(width 0.1524)
				(type default)
			)
			(layer "B.SilkS")
		)
		(fp_line
			(start 0.7874 -0.4064)
			(end -0.7874 -0.4064)
			(stroke
				(width 0.1524)
				(type default)
			)
			(layer "B.SilkS")
		)
		(fp_line
			(start -0.67945 0.3048)
			(end -0.120396 0.3048)
			(stroke
				(width 0.1)
				(type default)
			)
			(layer "B.Fab")
		)
		(fp_line
			(start -0.120396 0.3048)
			(end -0.120396 0.2794)
			(stroke
				(width 0.1)
				(type default)
			)
			(layer "B.Fab")
		)
		(fp_line
			(start 0.12065 0.3048)
			(end 0.67945 0.3048)
			(stroke
				(width 0.1)
				(type default)
			)
			(layer "B.Fab")
		)
		(fp_line
			(start 0.67945 0.3048)
			(end 0.67945 -0.305054)
			(stroke
				(width 0.1)
				(type default)
			)
			(layer "B.Fab")
		)
		(fp_line
			(start -0.120396 0.2794)
			(end 0.12065 0.2794)
			(stroke
				(width 0.1)
				(type default)
			)
			(layer "B.Fab")
		)
		(fp_line
			(start 0.12065 0.2794)
			(end 0.12065 0.3048)
			(stroke
				(width 0.1)
				(type default)
			)
			(layer "B.Fab")
		)
		(fp_line
			(start -0.12065 -0.2794)
			(end -0.12065 -0.3048)
			(stroke
				(width 0.1)
				(type default)
			)
			(layer "B.Fab")
		)
		(fp_line
			(start 0.12065 -0.2794)
			(end -0.12065 -0.2794)
			(stroke
				(width 0.1)
				(type default)
			)
			(layer "B.Fab")
		)
		(fp_line
			(start -0.67945 -0.3048)
			(end -0.67945 0.3048)
			(stroke
				(width 0.1)
				(type default)
			)
			(layer "B.Fab")
		)
		(fp_line
			(start -0.12065 -0.3048)
			(end -0.67945 -0.3048)
			(stroke
				(width 0.1)
				(type default)
			)
			(layer "B.Fab")
		)
		(fp_line
			(start 0.12065 -0.305054)
			(end 0.12065 -0.2794)
			(stroke
				(width 0.1)
				(type default)
			)
			(layer "B.Fab")
		)
		(fp_line
			(start 0.67945 -0.305054)
			(end 0.12065 -0.305054)
			(stroke
				(width 0.1)
				(type default)
			)
			(layer "B.Fab")
		)
		(pad "1" smd circle
			(at 0.40005 0 90)
			(size 0 0)
			(layers "B.Cu" "B.Mask" "B.Paste")
			(net "I3C_SCM_3_SDA")
		)
		(pad "2" smd circle
			(at -0.40005 0 90)
			(size 0 0)
			(layers "B.Cu" "B.Mask" "B.Paste")
			(net "I3C_SCM_3_R_SDA")
		)
	)
	(footprint ""
		(layer "B.Cu")
		(at 276.54377 -346.784168 90)
		(property "Reference" "PC182_4"
			(at 0 0 90)
			(layer "B.SilkS")
			(hide yes)
			(effects
				(font
					(size 1.27 1.27)
				)
				(justify mirror)
			)
		)
		(property "Value" ""
			(at 0 0 90)
			(layer "B.Fab")
			(effects
				(font
					(size 1.27 1.27)
				)
				(justify mirror)
			)
		)
		(duplicate_pad_numbers_are_jumpers no)
		(fp_line
			(start 1.524 -0.762)
			(end -1.524 -0.762)
			(stroke
				(width 0.1524)
				(type default)
			)
			(layer "B.SilkS")
		)
		(fp_line
			(start -1.524 -0.762)
			(end -1.524 0.762)
			(stroke
				(width 0.1524)
				(type default)
			)
			(layer "B.SilkS")
		)
		(fp_line
			(start 1.524 0.762)
			(end 1.524 -0.762)
			(stroke
				(width 0.1524)
				(type default)
			)
			(layer "B.SilkS")
		)
		(fp_line
			(start -1.524 0.762)
			(end 1.524 0.762)
			(stroke
				(width 0.1524)
				(type default)
			)
			(layer "B.SilkS")
		)
		(fp_line
			(start 1.1049 -0.724916)
			(end 1.1049 0.724916)
			(stroke
				(width 0.1)
				(type default)
			)
			(layer "B.Fab")
		)
		(fp_line
			(start -1.1049 -0.724916)
			(end 1.1049 -0.724916)
			(stroke
				(width 0.1)
				(type default)
			)
			(layer "B.Fab")
		)
		(fp_line
			(start 1.1049 0.724916)
			(end -1.1049 0.724916)
			(stroke
				(width 0.1)
				(type default)
			)
			(layer "B.Fab")
		)
		(fp_line
			(start -1.1049 0.724916)
			(end -1.1049 -0.724916)
			(stroke
				(width 0.1)
				(type default)
			)
			(layer "B.Fab")
		)
		(pad "1" smd rect
			(at 0.889 0 90)
			(size 1.016 1.27)
			(layers "B.Cu" "B.Mask" "B.Paste")
			(net "SW_P12V_AUX_PVDDIO_P0_FLT")
		)
		(pad "2" smd rect
			(at -0.889 0 90)
			(size 1.016 1.27)
			(layers "B.Cu" "B.Mask" "B.Paste")
			(net "GND")
		)
	)
	(footprint ""
		(layer "B.Cu")
		(at 336.279744 -156.059886 180)
		(property "Reference" "PC114"
			(at 0 0 0)
			(layer "B.SilkS")
			(hide yes)
			(effects
				(font
					(size 1.27 1.27)
				)
				(justify mirror)
			)
		)
		(property "Value" ""
			(at 0 0 0)
			(layer "B.Fab")
			(effects
				(font
					(size 1.27 1.27)
				)
				(justify mirror)
			)
		)
		(duplicate_pad_numbers_are_jumpers no)
		(fp_line
			(start 1.524 0.762)
			(end 1.524 -0.762)
			(stroke
				(width 0.1524)
				(type default)
			)
			(layer "B.SilkS")
		)
		(fp_line
			(start 1.524 -0.762)
			(end -1.524 -0.762)
			(stroke
				(width 0.1524)
				(type default)
			)
			(layer "B.SilkS")
		)
		(fp_line
			(start -1.524 0.762)
			(end 1.524 0.762)
			(stroke
				(width 0.1524)
				(type default)
			)
			(layer "B.SilkS")
		)
		(fp_line
			(start -1.524 -0.762)
			(end -1.524 0.762)
			(stroke
				(width 0.1524)
				(type default)
			)
			(layer "B.SilkS")
		)
		(fp_line
			(start 1.1049 0.724916)
			(end -1.1049 0.724916)
			(stroke
				(width 0.1)
				(type default)
			)
			(layer "B.Fab")
		)
		(fp_line
			(start 1.1049 -0.724916)
			(end 1.1049 0.724916)
			(stroke
				(width 0.1)
				(type default)
			)
			(layer "B.Fab")
		)
		(fp_line
			(start -1.1049 0.724916)
			(end -1.1049 -0.724916)
			(stroke
				(width 0.1)
				(type default)
			)
			(layer "B.Fab")
		)
		(fp_line
			(start -1.1049 -0.724916)
			(end 1.1049 -0.724916)
			(stroke
				(width 0.1)
				(type default)
			)
			(layer "B.Fab")
		)
		(pad "1" smd rect
			(at 0.889 0 180)
			(size 1.016 1.27)
			(layers "B.Cu" "B.Mask" "B.Paste")
			(net "PVDD18_S5_P0")
		)
		(pad "2" smd rect
			(at -0.889 0 180)
			(size 1.016 1.27)
			(layers "B.Cu" "B.Mask" "B.Paste")
			(net "GND")
		)
	)
)
